# BASEBOARD_FAB2 (Tioga Pass) — schematic netlist excerpt (pin names and nets, part order shuffled) for the footprints in the layout excerpt that follows; sources: Cadence DE-HDL packaged netlist, KiCad conversion of Wiwynn_Tioga_Pass_MB.brd

C6D10  CAP_A  22.0UF 4V 20% X6S  pkg 0603V  page 42 : A = PVCCIO_CPU0 ; B = GND
SH8L1  SHUNT  EMPTY  pkg SH0201  page 230 : A = VR_PVTT_KLM_SNS ; B = PVTT_KLM
R3F5  RES  0.0 5% EMPTY  pkg 0402  page 104 : A = CLK_322M_156M_CPU1_OSC_VRM_DN ; B = CLK_322M_OSC_CPU1_RC_DN

(kicad_pcb
	(version 20260206)
	(generator "pcbnew")
	(generator_version "10.0")
	(general
		(thickness 1.6)
		(legacy_teardrops no)
	)
	(paper "A4")
	(title_block
		(title "Wiwynn_Tioga_Pass_MB.brd")
		(comment 1 "Tioga Pass / footprints 987-989 of 4770")
	)
	(layers
		(0 "F.Cu" signal "TOP")
		(4 "In1.Cu" signal "L2GND")
		(6 "In2.Cu" signal "L3")
		(8 "In3.Cu" signal "L4GND")
		(10 "In4.Cu" signal "L5")
		(12 "In5.Cu" signal "L6GND")
		(14 "In6.Cu" signal "L7VCC")
		(16 "In7.Cu" signal "L8VCC")
		(18 "In8.Cu" signal "L9GND")
		(20 "In9.Cu" signal "L10")
		(22 "In10.Cu" signal "L11GND")
		(24 "In11.Cu" signal "L12")
		(26 "In12.Cu" signal "L13GND")
		(2 "B.Cu" signal "BOTTOM")
		(9 "F.Adhes" user "F.Adhesive")
		(11 "B.Adhes" user "B.Adhesive")
		(13 "F.Paste" user "Package Geometry/Pastemask Top")
		(15 "B.Paste" user "Package Geometry/Pastemask Bottom")
		(5 "F.SilkS" user "Ref Des/Silkscreen Top")
		(7 "B.SilkS" user "Ref Des/Silkscreen Bottom")
		(1 "F.Mask" user "Board Geometry/Soldermask Top")
		(3 "B.Mask" user "Board Geometry/Soldermask Bottom")
		(17 "Dwgs.User" user "User.Drawings")
		(19 "Cmts.User" user "User.Comments")
		(21 "Eco1.User" user "User.Eco1")
		(23 "Eco2.User" user "User.Eco2")
		(25 "Edge.Cuts" user "Board Geometry/Outline")
		(27 "Margin" user)
		(31 "F.CrtYd" user "Package Geometry/Place Bound Top")
		(29 "B.CrtYd" user "Package Geometry/Place Bound Bottom")
		(35 "F.Fab" user "Ref Des/Assembly Top")
		(33 "B.Fab" user "Ref Des/Assembly Bottom")
	)
	(footprint ""
		(layer "F.Cu")
		(at 155.194 -30.5308 -90)
		(property "Reference" "R3F5"
			(at 0 0 270)
			(layer "F.SilkS")
			(hide yes)
			(effects
				(font
					(size 1.27 1.27)
				)
			)
		)
		(property "Value" ""
			(at 0 0 270)
			(layer "F.Fab")
			(effects
				(font
					(size 1.27 1.27)
				)
			)
		)
		(duplicate_pad_numbers_are_jumpers no)
		(fp_poly
			(pts
				(xy -0.2794 -0.1016) (xy 0.2794 -0.1016) (xy 0.2794 0.9906) (xy -0.2794 0.9906)
			)
			(stroke
				(width 0)
				(type default)
			)
			(fill no)
			(layer "F.CrtYd")
		)
		(fp_line
			(start -0.2794 0.9906)
			(end 0.2794 0.9906)
			(stroke
				(width 0.1)
				(type default)
			)
			(layer "F.Fab")
		)
		(fp_line
			(start 0.2794 0.9906)
			(end 0.2794 -0.1016)
			(stroke
				(width 0.1)
				(type default)
			)
			(layer "F.Fab")
		)
		(fp_line
			(start -0.2794 -0.1016)
			(end -0.2794 0.9906)
			(stroke
				(width 0.1)
				(type default)
			)
			(layer "F.Fab")
		)
		(fp_line
			(start 0.2794 -0.1016)
			(end -0.2794 -0.1016)
			(stroke
				(width 0.1)
				(type default)
			)
			(layer "F.Fab")
		)
		(pad "1" smd rect
			(at 0 0 270)
			(size 0.508 0.508)
			(layers "F.Cu" "F.Mask" "F.Paste")
			(net "CLK_322M_156M_CPU1_OSC_VRM_DN")
		)
		(pad "2" smd rect
			(at 0 0.889 270)
			(size 0.508 0.508)
			(layers "F.Cu" "F.Mask" "F.Paste")
			(net "CLK_322M_OSC_CPU1_RC_DN")
		)
		(zone
			(layer "F.Cu")
			(hatch none 0.5)
			(connect_pads
				(clearance 0)
			)
			(min_thickness 0.25)
			(keepout
				(tracks not_allowed)
				(vias allowed)
				(pads allowed)
				(copperpour not_allowed)
				(footprints allowed)
			)
			(placement
				(enabled no)
				(sheetname "")
			)
			(fill
				(thermal_gap 0.5)
				(thermal_bridge_width 0.5)
				(island_removal_mode 0)
			)
			(polygon
				(pts
					(xy 154.559 -30.7848) (xy 154.559 -30.2768) (xy 154.94 -30.2768) (xy 154.94 -30.7848)
				)
			)
		)
		(zone
			(layer "F.Cu")
			(hatch none 0.5)
			(connect_pads
				(clearance 0)
			)
			(min_thickness 0.25)
			(keepout
				(tracks allowed)
				(vias not_allowed)
				(pads allowed)
				(copperpour not_allowed)
				(footprints allowed)
			)
			(placement
				(enabled no)
				(sheetname "")
			)
			(fill
				(thermal_gap 0.5)
				(thermal_bridge_width 0.5)
				(island_removal_mode 0)
			)
			(polygon
				(pts
					(xy 154.94 -30.7848) (xy 154.94 -30.2768) (xy 154.559 -30.2768) (xy 154.559 -30.7848)
				)
			)
		)
	)
	(footprint ""
		(layer "F.Cu")
		(at 97.72142 -158.1277 -90)
		(property "Reference" "SH8L1"
			(at 0 0 270)
			(layer "F.SilkS")
			(hide yes)
			(effects
				(font
					(size 1.27 1.27)
				)
			)
		)
		(property "Value" ""
			(at 0 0 270)
			(layer "F.Fab")
			(effects
				(font
					(size 1.27 1.27)
				)
			)
		)
		(duplicate_pad_numbers_are_jumpers no)
		(fp_poly
			(pts
				(xy -0.1651 -0.0508) (xy -0.1651 0.5842) (xy 0.1651 0.5842) (xy 0.1651 -0.0508)
			)
			(stroke
				(width 0)
				(type default)
			)
			(fill no)
			(layer "F.CrtYd")
		)
		(fp_line
			(start -0.1651 0.5842)
			(end -0.1651 -0.0508)
			(stroke
				(width 0.1)
				(type default)
			)
			(layer "F.Fab")
		)
		(fp_line
			(start 0.1651 0.5842)
			(end -0.1651 0.5842)
			(stroke
				(width 0.1)
				(type default)
			)
			(layer "F.Fab")
		)
		(fp_line
			(start -0.1651 -0.0508)
			(end 0.1651 -0.0508)
			(stroke
				(width 0.1)
				(type default)
			)
			(layer "F.Fab")
		)
		(fp_line
			(start 0.1651 -0.0508)
			(end 0.1651 0.5842)
			(stroke
				(width 0.1)
				(type default)
			)
			(layer "F.Fab")
		)
		(pad "1" smd custom
			(at 0 0 90)
			(size 0.0762 0.0762)
			(layers "F.Cu" "F.Mask" "F.Paste")
			(net "VR_PVTT_KLM_SNS")
			(options
				(clearance outline)
				(anchor circle)
			)
			(primitives
				(gr_poly
					(pts
						(arc
							(start -0.1524 -0.10795)
							(mid -0.098518 -0.130268)
							(end -0.0762 -0.18415)
						)
						(xy -0.0762 -0.22225) (xy 0.0762 -0.22225)
						(arc
							(start 0.0762 -0.18415)
							(mid 0.098518 -0.130268)
							(end 0.1524 -0.10795)
						)
						(xy 0.1524 0.22225) (xy -0.1524 0.22225)
					)
					(width 0)
					(fill yes)
				)
			)
		)
		(pad "2" smd custom
			(at 0 0.5334 270)
			(size 0.0762 0.0762)
			(layers "F.Cu" "F.Mask" "F.Paste")
			(net "PVTT_KLM")
			(options
				(clearance outline)
				(anchor circle)
			)
			(primitives
				(gr_poly
					(pts
						(arc
							(start -0.1524 -0.10795)
							(mid -0.098518 -0.130268)
							(end -0.0762 -0.18415)
						)
						(xy -0.0762 -0.22225) (xy 0.0762 -0.22225)
						(arc
							(start 0.0762 -0.18415)
							(mid 0.098518 -0.130268)
							(end 0.1524 -0.10795)
						)
						(xy 0.1524 0.22225) (xy -0.1524 0.22225)
					)
					(width 0)
					(fill yes)
				)
			)
		)
	)
	(footprint ""
		(layer "F.Cu")
		(at 280.138124 -71.714614 180)
		(property "Reference" "C6D10"
			(at 0 0 180)
			(layer "F.SilkS")
			(hide yes)
			(effects
				(font
					(size 1.27 1.27)
				)
			)
		)
		(property "Value" ""
			(at 0 0 180)
			(layer "F.Fab")
			(effects
				(font
					(size 1.27 1.27)
				)
			)
		)
		(duplicate_pad_numbers_are_jumpers no)
		(fp_poly
			(pts
				(xy -0.4953 -0.2032) (xy 0.4953 -0.2032) (xy 0.4953 1.6002) (xy -0.4953 1.6002)
			)
			(stroke
				(width 0)
				(type default)
			)
			(fill no)
			(layer "F.CrtYd")
		)
		(fp_line
			(start 0.4953 1.6002)
			(end -0.4953 1.6002)
			(stroke
				(width 0.1)
				(type default)
			)
			(layer "F.Fab")
		)
		(fp_line
			(start 0.4953 -0.2032)
			(end 0.4953 1.6002)
			(stroke
				(width 0.1)
				(type default)
			)
			(layer "F.Fab")
		)
		(fp_line
			(start -0.4953 1.6002)
			(end -0.4953 -0.2032)
			(stroke
				(width 0.1)
				(type default)
			)
			(layer "F.Fab")
		)
		(fp_line
			(start -0.4953 -0.2032)
			(end 0.4953 -0.2032)
			(stroke
				(width 0.1)
				(type default)
			)
			(layer "F.Fab")
		)
		(pad "1" smd rect
			(at 0 0 180)
			(size 0.762 0.889)
			(layers "F.Cu" "F.Mask" "F.Paste")
			(net "PVCCIO_CPU0")
		)
		(pad "2" smd rect
			(at 0 1.397 180)
			(size 0.762 0.889)
			(layers "F.Cu" "F.Mask" "F.Paste")
			(net "GND")
		)
		(zone
			(layer "F.Cu")
			(hatch none 0.5)
			(connect_pads
				(clearance 0)
			)
			(min_thickness 0.25)
			(keepout
				(tracks not_allowed)
				(vias allowed)
				(pads allowed)
				(copperpour not_allowed)
				(footprints allowed)
			)
			(placement
				(enabled no)
				(sheetname "")
			)
			(fill
				(thermal_gap 0.5)
				(thermal_bridge_width 0.5)
				(island_removal_mode 0)
			)
			(polygon
				(pts
					(xy 280.519124 -72.159114) (xy 279.757124 -72.159114) (xy 279.757124 -72.667114) (xy 280.519124 -72.667114)
				)
			)
		)
	)
)
